(kicad_pcb
	(version 20260206)
	(generator "pcbnew")
	(generator_version "10.0")
	(general
		(thickness 1.6)
		(legacy_teardrops no)
	)
	(paper "A4")
	(title_block
		(title "01162023_DA0F0TEBIF0_F0T_Expander_BD_F_brd_V02_OCP.brd")
		(comment 1 "Grand Teton / footprints 1841-1847 of 9728")
	)
	(layers
		(0 "F.Cu" signal "TOP")
		(4 "In1.Cu" signal "GND")
		(6 "In2.Cu" signal "VCC")
		(8 "In3.Cu" signal "VCC1")
		(10 "In4.Cu" signal "GND1")
		(12 "In5.Cu" signal "IN1")
		(14 "In6.Cu" signal "GND2")
		(16 "In7.Cu" signal "IN2")
		(18 "In8.Cu" signal "GND3")
		(20 "In9.Cu" signal "IN3")
		(22 "In10.Cu" signal "GND4")
		(24 "In11.Cu" signal "IN4")
		(26 "In12.Cu" signal "GND5")
		(28 "In13.Cu" signal "IN5")
		(30 "In14.Cu" signal "GND6")
		(32 "In15.Cu" signal "IN6")
		(34 "In16.Cu" signal "GND7")
		(2 "B.Cu" signal "BOTTOM")
		(9 "F.Adhes" user "F.Adhesive")
		(11 "B.Adhes" user "B.Adhesive")
		(13 "F.Paste" user "Package Geometry/Pastemask Top")
		(15 "B.Paste" user "Package Geometry/Pastemask Bottom")
		(5 "F.SilkS" user "Ref Des/Silkscreen Top")
		(7 "B.SilkS" user "Ref Des/Silkscreen Bottom")
		(1 "F.Mask" user "Board Geometry/Soldermask Top")
		(3 "B.Mask" user "Board Geometry/Soldermask Bottom")
		(17 "Dwgs.User" user "User.Drawings")
		(19 "Cmts.User" user "User.Comments")
		(21 "Eco1.User" user "User.Eco1")
		(23 "Eco2.User" user "User.Eco2")
		(25 "Edge.Cuts" user "Board Geometry/Outline")
		(27 "Margin" user)
		(31 "F.CrtYd" user "Package Geometry/Place Bound Top")
		(29 "B.CrtYd" user "Package Geometry/Place Bound Bottom")
		(35 "F.Fab" user "Ref Des/Assembly Top")
		(33 "B.Fab" user "Ref Des/Assembly Bottom")
	)
	(footprint ""
		(layer "F.Cu")
		(at 37.004752 -141.87297 180)
		(property "Reference" "R31"
			(at 0 0 180)
			(layer "F.SilkS")
			(hide yes)
			(effects
				(font
					(size 1.27 1.27)
				)
			)
		)
		(property "Value" ""
			(at 0 0 180)
			(layer "F.Fab")
			(effects
				(font
					(size 1.27 1.27)
				)
			)
		)
		(duplicate_pad_numbers_are_jumpers no)
		(fp_line
			(start 0.7874 0.4064)
			(end -0.7874 0.4064)
			(stroke
				(width 0.1524)
				(type default)
			)
			(layer "F.SilkS")
		)
		(fp_line
			(start 0.7874 -0.4064)
			(end 0.7874 0.4064)
			(stroke
				(width 0.1524)
				(type default)
			)
			(layer "F.SilkS")
		)
		(fp_line
			(start -0.7874 0.4064)
			(end -0.7874 -0.4064)
			(stroke
				(width 0.1524)
				(type default)
			)
			(layer "F.SilkS")
		)
		(fp_line
			(start -0.7874 -0.4064)
			(end 0.7874 -0.4064)
			(stroke
				(width 0.1524)
				(type default)
			)
			(layer "F.SilkS")
		)
		(fp_line
			(start 0.67945 0.3048)
			(end 0.120396 0.3048)
			(stroke
				(width 0.1)
				(type default)
			)
			(layer "F.Fab")
		)
		(fp_line
			(start 0.67945 -0.3048)
			(end 0.67945 0.3048)
			(stroke
				(width 0.1)
				(type default)
			)
			(layer "F.Fab")
		)
		(fp_line
			(start 0.12065 -0.2794)
			(end 0.12065 -0.3048)
			(stroke
				(width 0.1)
				(type default)
			)
			(layer "F.Fab")
		)
		(fp_line
			(start 0.12065 -0.3048)
			(end 0.67945 -0.3048)
			(stroke
				(width 0.1)
				(type default)
			)
			(layer "F.Fab")
		)
		(fp_line
			(start 0.120396 0.3048)
			(end 0.120396 0.2794)
			(stroke
				(width 0.1)
				(type default)
			)
			(layer "F.Fab")
		)
		(fp_line
			(start 0.120396 0.2794)
			(end -0.12065 0.2794)
			(stroke
				(width 0.1)
				(type default)
			)
			(layer "F.Fab")
		)
		(fp_line
			(start -0.12065 0.3048)
			(end -0.67945 0.3048)
			(stroke
				(width 0.1)
				(type default)
			)
			(layer "F.Fab")
		)
		(fp_line
			(start -0.12065 0.2794)
			(end -0.12065 0.3048)
			(stroke
				(width 0.1)
				(type default)
			)
			(layer "F.Fab")
		)
		(fp_line
			(start -0.12065 -0.2794)
			(end 0.12065 -0.2794)
			(stroke
				(width 0.1)
				(type default)
			)
			(layer "F.Fab")
		)
		(fp_line
			(start -0.12065 -0.305054)
			(end -0.12065 -0.2794)
			(stroke
				(width 0.1)
				(type default)
			)
			(layer "F.Fab")
		)
		(fp_line
			(start -0.67945 0.3048)
			(end -0.67945 -0.305054)
			(stroke
				(width 0.1)
				(type default)
			)
			(layer "F.Fab")
		)
		(fp_line
			(start -0.67945 -0.305054)
			(end -0.12065 -0.305054)
			(stroke
				(width 0.1)
				(type default)
			)
			(layer "F.Fab")
		)
		(pad "1" smd circle
			(at -0.40005 0 180)
			(size 0 0)
			(layers "F.Cu" "F.Mask" "F.Paste")
			(net "NIC0_BIF1_N")
		)
		(pad "2" smd circle
			(at 0.40005 0 180)
			(size 0 0)
			(layers "F.Cu" "F.Mask" "F.Paste")
			(net "P3V3_AUX")
		)
	)
	(footprint ""
		(layer "F.Cu")
		(at 180.814472 -350.098614 90)
		(property "Reference" "C2530"
			(at 0 0 90)
			(layer "F.SilkS")
			(hide yes)
			(effects
				(font
					(size 1.27 1.27)
				)
			)
		)
		(property "Value" ""
			(at 0 0 90)
			(layer "F.Fab")
			(effects
				(font
					(size 1.27 1.27)
				)
			)
		)
		(duplicate_pad_numbers_are_jumpers no)
		(fp_line
			(start 0.299974 -0.150114)
			(end 0.299974 0.150114)
			(stroke
				(width 0.1)
				(type default)
			)
			(layer "F.Fab")
		)
		(fp_line
			(start -0.299974 -0.150114)
			(end 0.299974 -0.150114)
			(stroke
				(width 0.1)
				(type default)
			)
			(layer "F.Fab")
		)
		(fp_line
			(start 0.299974 0.150114)
			(end -0.299974 0.150114)
			(stroke
				(width 0.1)
				(type default)
			)
			(layer "F.Fab")
		)
		(fp_line
			(start -0.299974 0.150114)
			(end -0.299974 -0.150114)
			(stroke
				(width 0.1)
				(type default)
			)
			(layer "F.Fab")
		)
		(pad "1" smd rect
			(at -0.2667 0 90)
			(size 0.3048 0.381)
			(layers "F.Cu" "F.Mask" "F.Paste")
			(net "P5E_PEX1_STN4_TX_DP<70>")
		)
		(pad "2" smd rect
			(at 0.2667 0 90)
			(size 0.3048 0.381)
			(layers "F.Cu" "F.Mask" "F.Paste")
			(net "P5E_PEX1_STN4_TX_C_DP<70>")
		)
	)
	(footprint ""
		(layer "F.Cu")
		(at 197.25513 -53.468524 90)
		(property "Reference" "PC497"
			(at 0 0 90)
			(layer "F.SilkS")
			(hide yes)
			(effects
				(font
					(size 1.27 1.27)
				)
			)
		)
		(property "Value" ""
			(at 0 0 90)
			(layer "F.Fab")
			(effects
				(font
					(size 1.27 1.27)
				)
			)
		)
		(duplicate_pad_numbers_are_jumpers no)
		(fp_line
			(start 1.524 -0.762)
			(end 1.524 0.762)
			(stroke
				(width 0.1524)
				(type default)
			)
			(layer "F.SilkS")
		)
		(fp_line
			(start -1.524 -0.762)
			(end 1.524 -0.762)
			(stroke
				(width 0.1524)
				(type default)
			)
			(layer "F.SilkS")
		)
		(fp_line
			(start 1.524 0.762)
			(end -1.524 0.762)
			(stroke
				(width 0.1524)
				(type default)
			)
			(layer "F.SilkS")
		)
		(fp_line
			(start -1.524 0.762)
			(end -1.524 -0.762)
			(stroke
				(width 0.1524)
				(type default)
			)
			(layer "F.SilkS")
		)
		(fp_line
			(start 1.1049 -0.724916)
			(end -1.1049 -0.724916)
			(stroke
				(width 0.1)
				(type default)
			)
			(layer "F.Fab")
		)
		(fp_line
			(start -1.1049 -0.724916)
			(end -1.1049 0.724916)
			(stroke
				(width 0.1)
				(type default)
			)
			(layer "F.Fab")
		)
		(fp_line
			(start 1.1049 0.724916)
			(end 1.1049 -0.724916)
			(stroke
				(width 0.1)
				(type default)
			)
			(layer "F.Fab")
		)
		(fp_line
			(start -1.1049 0.724916)
			(end 1.1049 0.724916)
			(stroke
				(width 0.1)
				(type default)
			)
			(layer "F.Fab")
		)
		(pad "1" smd rect
			(at -0.889 0 270)
			(size 1.016 1.27)
			(layers "F.Cu" "F.Mask" "F.Paste")
			(net "GND")
		)
		(pad "2" smd rect
			(at 0.889 0 270)
			(size 1.016 1.27)
			(layers "F.Cu" "F.Mask" "F.Paste")
			(net "P3V3_AUX")
		)
	)
	(footprint ""
		(layer "F.Cu")
		(at 404.172166 -32.848042 90)
		(property "Reference" "PC971"
			(at 0 0 90)
			(layer "F.SilkS")
			(hide yes)
			(effects
				(font
					(size 1.27 1.27)
				)
			)
		)
		(property "Value" ""
			(at 0 0 90)
			(layer "F.Fab")
			(effects
				(font
					(size 1.27 1.27)
				)
			)
		)
		(duplicate_pad_numbers_are_jumpers no)
		(fp_line
			(start 0.7874 -0.4064)
			(end 0.7874 0.4064)
			(stroke
				(width 0.1524)
				(type default)
			)
			(layer "F.SilkS")
		)
		(fp_line
			(start -0.7874 -0.4064)
			(end 0.7874 -0.4064)
			(stroke
				(width 0.1524)
				(type default)
			)
			(layer "F.SilkS")
		)
		(fp_line
			(start 0.7874 0.4064)
			(end -0.7874 0.4064)
			(stroke
				(width 0.1524)
				(type default)
			)
			(layer "F.SilkS")
		)
		(fp_line
			(start -0.7874 0.4064)
			(end -0.7874 -0.4064)
			(stroke
				(width 0.1524)
				(type default)
			)
			(layer "F.SilkS")
		)
		(fp_line
			(start -0.12065 -0.305054)
			(end -0.12065 -0.2794)
			(stroke
				(width 0.1)
				(type default)
			)
			(layer "F.Fab")
		)
		(fp_line
			(start -0.67945 -0.305054)
			(end -0.12065 -0.305054)
			(stroke
				(width 0.1)
				(type default)
			)
			(layer "F.Fab")
		)
		(fp_line
			(start 0.67945 -0.3048)
			(end 0.67945 0.3048)
			(stroke
				(width 0.1)
				(type default)
			)
			(layer "F.Fab")
		)
		(fp_line
			(start 0.12065 -0.3048)
			(end 0.67945 -0.3048)
			(stroke
				(width 0.1)
				(type default)
			)
			(layer "F.Fab")
		)
		(fp_line
			(start 0.12065 -0.2794)
			(end 0.12065 -0.3048)
			(stroke
				(width 0.1)
				(type default)
			)
			(layer "F.Fab")
		)
		(fp_line
			(start -0.12065 -0.2794)
			(end 0.12065 -0.2794)
			(stroke
				(width 0.1)
				(type default)
			)
			(layer "F.Fab")
		)
		(fp_line
			(start 0.120396 0.2794)
			(end -0.12065 0.2794)
			(stroke
				(width 0.1)
				(type default)
			)
			(layer "F.Fab")
		)
		(fp_line
			(start -0.12065 0.2794)
			(end -0.12065 0.3048)
			(stroke
				(width 0.1)
				(type default)
			)
			(layer "F.Fab")
		)
		(fp_line
			(start 0.67945 0.3048)
			(end 0.120396 0.3048)
			(stroke
				(width 0.1)
				(type default)
			)
			(layer "F.Fab")
		)
		(fp_line
			(start 0.120396 0.3048)
			(end 0.120396 0.2794)
			(stroke
				(width 0.1)
				(type default)
			)
			(layer "F.Fab")
		)
		(fp_line
			(start -0.12065 0.3048)
			(end -0.67945 0.3048)
			(stroke
				(width 0.1)
				(type default)
			)
			(layer "F.Fab")
		)
		(fp_line
			(start -0.67945 0.3048)
			(end -0.67945 -0.305054)
			(stroke
				(width 0.1)
				(type default)
			)
			(layer "F.Fab")
		)
		(pad "1" smd circle
			(at -0.40005 0 90)
			(size 0 0)
			(layers "F.Cu" "F.Mask" "F.Paste")
			(net "P3V3_SSD14_CO_GATE")
		)
		(pad "2" smd circle
			(at 0.40005 0 90)
			(size 0 0)
			(layers "F.Cu" "F.Mask" "F.Paste")
			(net "GND")
		)
	)
	(footprint ""
		(layer "F.Cu")
		(at 129.129282 -280.44902 -90)
		(property "Reference" "PC115"
			(at 0 0 270)
			(layer "F.SilkS")
			(hide yes)
			(effects
				(font
					(size 1.27 1.27)
				)
			)
		)
		(property "Value" ""
			(at 0 0 270)
			(layer "F.Fab")
			(effects
				(font
					(size 1.27 1.27)
				)
			)
		)
		(duplicate_pad_numbers_are_jumpers no)
		(fp_line
			(start -0.7874 0.4064)
			(end -0.7874 -0.4064)
			(stroke
				(width 0.1524)
				(type default)
			)
			(layer "F.SilkS")
		)
		(fp_line
			(start 0.7874 0.4064)
			(end -0.7874 0.4064)
			(stroke
				(width 0.1524)
				(type default)
			)
			(layer "F.SilkS")
		)
		(fp_line
			(start -0.7874 -0.4064)
			(end 0.7874 -0.4064)
			(stroke
				(width 0.1524)
				(type default)
			)
			(layer "F.SilkS")
		)
		(fp_line
			(start 0.7874 -0.4064)
			(end 0.7874 0.4064)
			(stroke
				(width 0.1524)
				(type default)
			)
			(layer "F.SilkS")
		)
		(fp_line
			(start -0.67945 0.3048)
			(end -0.67945 -0.305054)
			(stroke
				(width 0.1)
				(type default)
			)
			(layer "F.Fab")
		)
		(fp_line
			(start -0.12065 0.3048)
			(end -0.67945 0.3048)
			(stroke
				(width 0.1)
				(type default)
			)
			(layer "F.Fab")
		)
		(fp_line
			(start 0.120396 0.3048)
			(end 0.120396 0.2794)
			(stroke
				(width 0.1)
				(type default)
			)
			(layer "F.Fab")
		)
		(fp_line
			(start 0.67945 0.3048)
			(end 0.120396 0.3048)
			(stroke
				(width 0.1)
				(type default)
			)
			(layer "F.Fab")
		)
		(fp_line
			(start -0.12065 0.2794)
			(end -0.12065 0.3048)
			(stroke
				(width 0.1)
				(type default)
			)
			(layer "F.Fab")
		)
		(fp_line
			(start 0.120396 0.2794)
			(end -0.12065 0.2794)
			(stroke
				(width 0.1)
				(type default)
			)
			(layer "F.Fab")
		)
		(fp_line
			(start -0.12065 -0.2794)
			(end 0.12065 -0.2794)
			(stroke
				(width 0.1)
				(type default)
			)
			(layer "F.Fab")
		)
		(fp_line
			(start 0.12065 -0.2794)
			(end 0.12065 -0.3048)
			(stroke
				(width 0.1)
				(type default)
			)
			(layer "F.Fab")
		)
		(fp_line
			(start 0.12065 -0.3048)
			(end 0.67945 -0.3048)
			(stroke
				(width 0.1)
				(type default)
			)
			(layer "F.Fab")
		)
		(fp_line
			(start 0.67945 -0.3048)
			(end 0.67945 0.3048)
			(stroke
				(width 0.1)
				(type default)
			)
			(layer "F.Fab")
		)
		(fp_line
			(start -0.67945 -0.305054)
			(end -0.12065 -0.305054)
			(stroke
				(width 0.1)
				(type default)
			)
			(layer "F.Fab")
		)
		(fp_line
			(start -0.12065 -0.305054)
			(end -0.12065 -0.2794)
			(stroke
				(width 0.1)
				(type default)
			)
			(layer "F.Fab")
		)
		(pad "1" smd circle
			(at -0.40005 0 270)
			(size 0 0)
			(layers "F.Cu" "F.Mask" "F.Paste")
			(net "SW_P0V8_PEX1_PHASE2")
		)
		(pad "2" smd circle
			(at 0.40005 0 270)
			(size 0 0)
			(layers "F.Cu" "F.Mask" "F.Paste")
			(net "SW_P0V8_PEX1_BOOT2_R")
		)
	)
	(footprint ""
		(layer "F.Cu")
		(at 218.247468 -251.163836 -90)
		(property "Reference" "C4300"
			(at 0 0 270)
			(layer "F.SilkS")
			(hide yes)
			(effects
				(font
					(size 1.27 1.27)
				)
			)
		)
		(property "Value" ""
			(at 0 0 270)
			(layer "F.Fab")
			(effects
				(font
					(size 1.27 1.27)
				)
			)
		)
		(duplicate_pad_numbers_are_jumpers no)
		(fp_line
			(start -1.524 0.762)
			(end -1.524 -0.762)
			(stroke
				(width 0.1524)
				(type default)
			)
			(layer "F.SilkS")
		)
		(fp_line
			(start 1.524 0.762)
			(end -1.524 0.762)
			(stroke
				(width 0.1524)
				(type default)
			)
			(layer "F.SilkS")
		)
		(fp_line
			(start -1.524 -0.762)
			(end 1.524 -0.762)
			(stroke
				(width 0.1524)
				(type default)
			)
			(layer "F.SilkS")
		)
		(fp_line
			(start 1.524 -0.762)
			(end 1.524 0.762)
			(stroke
				(width 0.1524)
				(type default)
			)
			(layer "F.SilkS")
		)
		(fp_line
			(start -1.1049 0.724916)
			(end 1.1049 0.724916)
			(stroke
				(width 0.1)
				(type default)
			)
			(layer "F.Fab")
		)
		(fp_line
			(start 1.1049 0.724916)
			(end 1.1049 -0.724916)
			(stroke
				(width 0.1)
				(type default)
			)
			(layer "F.Fab")
		)
		(fp_line
			(start -1.1049 -0.724916)
			(end -1.1049 0.724916)
			(stroke
				(width 0.1)
				(type default)
			)
			(layer "F.Fab")
		)
		(fp_line
			(start 1.1049 -0.724916)
			(end -1.1049 -0.724916)
			(stroke
				(width 0.1)
				(type default)
			)
			(layer "F.Fab")
		)
		(pad "1" smd rect
			(at -0.889 0 90)
			(size 1.016 1.27)
			(layers "F.Cu" "F.Mask" "F.Paste")
			(net "P1V25_SERDES_VDDPLL_PEX1_C10")
		)
		(pad "2" smd rect
			(at 0.889 0 90)
			(size 1.016 1.27)
			(layers "F.Cu" "F.Mask" "F.Paste")
			(net "GND")
		)
		(zone
			(layer "F.Cu")
			(hatch none 0.5)
			(connect_pads
				(clearance 0)
			)
			(min_thickness 0.25)
			(keepout
				(tracks not_allowed)
				(vias allowed)
				(pads allowed)
				(copperpour not_allowed)
				(footprints allowed)
			)
			(placement
				(enabled no)
				(sheetname "")
			)
			(fill
				(thermal_gap 0.5)
				(thermal_bridge_width 0.5)
				(island_removal_mode 0)
			)
			(polygon
				(pts
					(xy 218.972384 -251.494036) (xy 217.522552 -251.494036) (xy 217.522552 -250.833636) (xy 218.972384 -250.833636)
				)
			)
		)
	)
	(footprint ""
		(layer "F.Cu")
		(at 381.254 -206.502 180)
		(property "Reference" "R4615"
			(at 0 0 180)
			(layer "F.SilkS")
			(hide yes)
			(effects
				(font
					(size 1.27 1.27)
				)
			)
		)
		(property "Value" ""
			(at 0 0 180)
			(layer "F.Fab")
			(effects
				(font
					(size 1.27 1.27)
				)
			)
		)
		(duplicate_pad_numbers_are_jumpers no)
		(fp_line
			(start 0.7874 0.4064)
			(end -0.7874 0.4064)
			(stroke
				(width 0.1524)
				(type default)
			)
			(layer "F.SilkS")
		)
		(fp_line
			(start 0.7874 -0.4064)
			(end 0.7874 0.4064)
			(stroke
				(width 0.1524)
				(type default)
			)
			(layer "F.SilkS")
		)
		(fp_line
			(start -0.7874 0.4064)
			(end -0.7874 -0.4064)
			(stroke
				(width 0.1524)
				(type default)
			)
			(layer "F.SilkS")
		)
		(fp_line
			(start -0.7874 -0.4064)
			(end 0.7874 -0.4064)
			(stroke
				(width 0.1524)
				(type default)
			)
			(layer "F.SilkS")
		)
		(fp_line
			(start 0.67945 0.3048)
			(end 0.120396 0.3048)
			(stroke
				(width 0.1)
				(type default)
			)
			(layer "F.Fab")
		)
		(fp_line
			(start 0.67945 -0.3048)
			(end 0.67945 0.3048)
			(stroke
				(width 0.1)
				(type default)
			)
			(layer "F.Fab")
		)
		(fp_line
			(start 0.12065 -0.2794)
			(end 0.12065 -0.3048)
			(stroke
				(width 0.1)
				(type default)
			)
			(layer "F.Fab")
		)
		(fp_line
			(start 0.12065 -0.3048)
			(end 0.67945 -0.3048)
			(stroke
				(width 0.1)
				(type default)
			)
			(layer "F.Fab")
		)
		(fp_line
			(start 0.120396 0.3048)
			(end 0.120396 0.2794)
			(stroke
				(width 0.1)
				(type default)
			)
			(layer "F.Fab")
		)
		(fp_line
			(start 0.120396 0.2794)
			(end -0.12065 0.2794)
			(stroke
				(width 0.1)
				(type default)
			)
			(layer "F.Fab")
		)
		(fp_line
			(start -0.12065 0.3048)
			(end -0.67945 0.3048)
			(stroke
				(width 0.1)
				(type default)
			)
			(layer "F.Fab")
		)
		(fp_line
			(start -0.12065 0.2794)
			(end -0.12065 0.3048)
			(stroke
				(width 0.1)
				(type default)
			)
			(layer "F.Fab")
		)
		(fp_line
			(start -0.12065 -0.2794)
			(end 0.12065 -0.2794)
			(stroke
				(width 0.1)
				(type default)
			)
			(layer "F.Fab")
		)
		(fp_line
			(start -0.12065 -0.305054)
			(end -0.12065 -0.2794)
			(stroke
				(width 0.1)
				(type default)
			)
			(layer "F.Fab")
		)
		(fp_line
			(start -0.67945 0.3048)
			(end -0.67945 -0.305054)
			(stroke
				(width 0.1)
				(type default)
			)
			(layer "F.Fab")
		)
		(fp_line
			(start -0.67945 -0.305054)
			(end -0.12065 -0.305054)
			(stroke
				(width 0.1)
				(type default)
			)
			(layer "F.Fab")
		)
		(pad "1" smd circle
			(at -0.40005 0 180)
			(size 0 0)
			(layers "F.Cu" "F.Mask" "F.Paste")
			(net "NIC0_PEX_PWR_EN_R")
		)
		(pad "2" smd circle
			(at 0.40005 0 180)
			(size 0 0)
			(layers "F.Cu" "F.Mask" "F.Paste")
			(net "GND")
		)
	)
)
